# T6G (Grand Teton) — schematic netlist excerpt (pin names and nets, part order shuffled) for the footprints in the layout excerpt that follows; sources: Cadence DE-HDL packaged netlist, KiCad conversion of 04192023_DAF0TMB3IC0_F0TG_MB_C_brd_V02_OCP.brd

R8421  Q_RES  10K 1% CHIP  pkg 0402LF  page 131 : A = SGPIO_OCP_SFF_DATAIN ; B = P3V3_OCP_SFF
R1383  Q_RES  4.7K 5% CHIP  pkg 0201LF  page 185 : A = P1V8_CPU0_RT_1D ; B = SMB_RT_CPU0_P2_ROM_MUX_2D_R_SCL
C2463  Q_CAP  22UF 4V 20% X6S  pkg C0402  page 74 : A = PVDDCR_SOC_P1 ; B = GND

(kicad_pcb
	(version 20260206)
	(generator "pcbnew")
	(generator_version "10.0")
	(general
		(thickness 1.6)
		(legacy_teardrops no)
	)
	(paper "A4")
	(title_block
		(title "04192023_DAF0TMB3IC0_F0TG_MB_C_brd_V02_OCP.brd")
		(comment 1 "Grand Teton / footprints 6563-6565 of 8354")
	)
	(layers
		(0 "F.Cu" signal "TOP")
		(4 "In1.Cu" signal "GND")
		(6 "In2.Cu" signal "IN1")
		(8 "In3.Cu" signal "GND1")
		(10 "In4.Cu" signal "IN2")
		(12 "In5.Cu" signal "GND2")
		(14 "In6.Cu" signal "IN3")
		(16 "In7.Cu" signal "GND3")
		(18 "In8.Cu" signal "VCC")
		(20 "In9.Cu" signal "VCC1")
		(22 "In10.Cu" signal "GND4")
		(24 "In11.Cu" signal "IN4")
		(26 "In12.Cu" signal "GND5")
		(28 "In13.Cu" signal "IN5")
		(30 "In14.Cu" signal "GND6")
		(32 "In15.Cu" signal "IN6")
		(34 "In16.Cu" signal "GND7")
		(2 "B.Cu" signal "BOTTOM")
		(9 "F.Adhes" user "F.Adhesive")
		(11 "B.Adhes" user "B.Adhesive")
		(13 "F.Paste" user "Package Geometry/Pastemask Top")
		(15 "B.Paste" user "Package Geometry/Pastemask Bottom")
		(5 "F.SilkS" user "Ref Des/Silkscreen Top")
		(7 "B.SilkS" user "Ref Des/Silkscreen Bottom")
		(1 "F.Mask" user "Board Geometry/Soldermask Top")
		(3 "B.Mask" user "Board Geometry/Soldermask Bottom")
		(17 "Dwgs.User" user "User.Drawings")
		(19 "Cmts.User" user "User.Comments")
		(21 "Eco1.User" user "User.Eco1")
		(23 "Eco2.User" user "User.Eco2")
		(25 "Edge.Cuts" user "Board Geometry/Outline")
		(27 "Margin" user)
		(31 "F.CrtYd" user "Package Geometry/Place Bound Top")
		(29 "B.CrtYd" user "Package Geometry/Place Bound Bottom")
		(35 "F.Fab" user "Ref Des/Assembly Top")
		(33 "B.Fab" user "Ref Des/Assembly Bottom")
	)
	(footprint ""
		(layer "B.Cu")
		(at 117.895624 -260.305296)
		(property "Reference" "C2463"
			(at 0 0 0)
			(layer "B.SilkS")
			(hide yes)
			(effects
				(font
					(size 1.27 1.27)
				)
				(justify mirror)
			)
		)
		(property "Value" ""
			(at 0 0 0)
			(layer "B.Fab")
			(effects
				(font
					(size 1.27 1.27)
				)
				(justify mirror)
			)
		)
		(duplicate_pad_numbers_are_jumpers no)
		(fp_line
			(start -0.7874 -0.4064)
			(end -0.7874 0.4064)
			(stroke
				(width 0.1524)
				(type default)
			)
			(layer "B.SilkS")
		)
		(fp_line
			(start -0.7874 0.4064)
			(end 0.7874 0.4064)
			(stroke
				(width 0.1524)
				(type default)
			)
			(layer "B.SilkS")
		)
		(fp_line
			(start 0.7874 -0.4064)
			(end -0.7874 -0.4064)
			(stroke
				(width 0.1524)
				(type default)
			)
			(layer "B.SilkS")
		)
		(fp_line
			(start 0.7874 0.4064)
			(end 0.7874 -0.4064)
			(stroke
				(width 0.1524)
				(type default)
			)
			(layer "B.SilkS")
		)
		(fp_line
			(start -0.67945 -0.3048)
			(end -0.67945 0.3048)
			(stroke
				(width 0.1)
				(type default)
			)
			(layer "B.Fab")
		)
		(fp_line
			(start -0.67945 0.3048)
			(end -0.120396 0.3048)
			(stroke
				(width 0.1)
				(type default)
			)
			(layer "B.Fab")
		)
		(fp_line
			(start -0.12065 -0.3048)
			(end -0.67945 -0.3048)
			(stroke
				(width 0.1)
				(type default)
			)
			(layer "B.Fab")
		)
		(fp_line
			(start -0.12065 -0.2794)
			(end -0.12065 -0.3048)
			(stroke
				(width 0.1)
				(type default)
			)
			(layer "B.Fab")
		)
		(fp_line
			(start -0.120396 0.2794)
			(end 0.12065 0.2794)
			(stroke
				(width 0.1)
				(type default)
			)
			(layer "B.Fab")
		)
		(fp_line
			(start -0.120396 0.3048)
			(end -0.120396 0.2794)
			(stroke
				(width 0.1)
				(type default)
			)
			(layer "B.Fab")
		)
		(fp_line
			(start 0.12065 -0.305054)
			(end 0.12065 -0.2794)
			(stroke
				(width 0.1)
				(type default)
			)
			(layer "B.Fab")
		)
		(fp_line
			(start 0.12065 -0.2794)
			(end -0.12065 -0.2794)
			(stroke
				(width 0.1)
				(type default)
			)
			(layer "B.Fab")
		)
		(fp_line
			(start 0.12065 0.2794)
			(end 0.12065 0.3048)
			(stroke
				(width 0.1)
				(type default)
			)
			(layer "B.Fab")
		)
		(fp_line
			(start 0.12065 0.3048)
			(end 0.67945 0.3048)
			(stroke
				(width 0.1)
				(type default)
			)
			(layer "B.Fab")
		)
		(fp_line
			(start 0.67945 -0.305054)
			(end 0.12065 -0.305054)
			(stroke
				(width 0.1)
				(type default)
			)
			(layer "B.Fab")
		)
		(fp_line
			(start 0.67945 0.3048)
			(end 0.67945 -0.305054)
			(stroke
				(width 0.1)
				(type default)
			)
			(layer "B.Fab")
		)
		(pad "1" smd circle
			(at 0.40005 0 180)
			(size 0 0)
			(layers "B.Cu" "B.Mask" "B.Paste")
			(net "PVDDCR_SOC_P1")
		)
		(pad "2" smd circle
			(at -0.40005 0 180)
			(size 0 0)
			(layers "B.Cu" "B.Mask" "B.Paste")
			(net "GND")
		)
	)
	(footprint ""
		(layer "B.Cu")
		(at 451.549516 -10.634726 90)
		(property "Reference" "R8421"
			(at 0 0 90)
			(layer "B.SilkS")
			(hide yes)
			(effects
				(font
					(size 1.27 1.27)
				)
				(justify mirror)
			)
		)
		(property "Value" ""
			(at 0 0 90)
			(layer "B.Fab")
			(effects
				(font
					(size 1.27 1.27)
				)
				(justify mirror)
			)
		)
		(duplicate_pad_numbers_are_jumpers no)
		(fp_line
			(start 0.7874 -0.4064)
			(end -0.7874 -0.4064)
			(stroke
				(width 0.1524)
				(type default)
			)
			(layer "B.SilkS")
		)
		(fp_line
			(start -0.7874 -0.4064)
			(end -0.7874 0.4064)
			(stroke
				(width 0.1524)
				(type default)
			)
			(layer "B.SilkS")
		)
		(fp_line
			(start 0.7874 0.4064)
			(end 0.7874 -0.4064)
			(stroke
				(width 0.1524)
				(type default)
			)
			(layer "B.SilkS")
		)
		(fp_line
			(start -0.7874 0.4064)
			(end 0.7874 0.4064)
			(stroke
				(width 0.1524)
				(type default)
			)
			(layer "B.SilkS")
		)
		(fp_line
			(start 0.67945 -0.305054)
			(end 0.12065 -0.305054)
			(stroke
				(width 0.1)
				(type default)
			)
			(layer "B.Fab")
		)
		(fp_line
			(start 0.12065 -0.305054)
			(end 0.12065 -0.2794)
			(stroke
				(width 0.1)
				(type default)
			)
			(layer "B.Fab")
		)
		(fp_line
			(start -0.12065 -0.3048)
			(end -0.67945 -0.3048)
			(stroke
				(width 0.1)
				(type default)
			)
			(layer "B.Fab")
		)
		(fp_line
			(start -0.67945 -0.3048)
			(end -0.67945 0.3048)
			(stroke
				(width 0.1)
				(type default)
			)
			(layer "B.Fab")
		)
		(fp_line
			(start 0.12065 -0.2794)
			(end -0.12065 -0.2794)
			(stroke
				(width 0.1)
				(type default)
			)
			(layer "B.Fab")
		)
		(fp_line
			(start -0.12065 -0.2794)
			(end -0.12065 -0.3048)
			(stroke
				(width 0.1)
				(type default)
			)
			(layer "B.Fab")
		)
		(fp_line
			(start 0.12065 0.2794)
			(end 0.12065 0.3048)
			(stroke
				(width 0.1)
				(type default)
			)
			(layer "B.Fab")
		)
		(fp_line
			(start -0.120396 0.2794)
			(end 0.12065 0.2794)
			(stroke
				(width 0.1)
				(type default)
			)
			(layer "B.Fab")
		)
		(fp_line
			(start 0.67945 0.3048)
			(end 0.67945 -0.305054)
			(stroke
				(width 0.1)
				(type default)
			)
			(layer "B.Fab")
		)
		(fp_line
			(start 0.12065 0.3048)
			(end 0.67945 0.3048)
			(stroke
				(width 0.1)
				(type default)
			)
			(layer "B.Fab")
		)
		(fp_line
			(start -0.120396 0.3048)
			(end -0.120396 0.2794)
			(stroke
				(width 0.1)
				(type default)
			)
			(layer "B.Fab")
		)
		(fp_line
			(start -0.67945 0.3048)
			(end -0.120396 0.3048)
			(stroke
				(width 0.1)
				(type default)
			)
			(layer "B.Fab")
		)
		(pad "1" smd circle
			(at 0.40005 0 270)
			(size 0 0)
			(layers "B.Cu" "B.Mask" "B.Paste")
			(net "SGPIO_OCP_SFF_DATAIN")
		)
		(pad "2" smd circle
			(at -0.40005 0 270)
			(size 0 0)
			(layers "B.Cu" "B.Mask" "B.Paste")
			(net "P3V3_OCP_SFF")
		)
	)
	(footprint ""
		(layer "B.Cu")
		(at 254.635 -334.01 180)
		(property "Reference" "R1383"
			(at 0 0 0)
			(layer "B.SilkS")
			(hide yes)
			(effects
				(font
					(size 1.27 1.27)
				)
				(justify mirror)
			)
		)
		(property "Value" ""
			(at 0 0 0)
			(layer "B.Fab")
			(effects
				(font
					(size 1.27 1.27)
				)
				(justify mirror)
			)
		)
		(duplicate_pad_numbers_are_jumpers no)
		(fp_line
			(start 0.32512 0.175006)
			(end 0.32512 -0.175006)
			(stroke
				(width 0.1)
				(type default)
			)
			(layer "B.Fab")
		)
		(fp_line
			(start 0.32512 -0.175006)
			(end -0.32512 -0.175006)
			(stroke
				(width 0.1)
				(type default)
			)
			(layer "B.Fab")
		)
		(fp_line
			(start -0.32512 0.175006)
			(end 0.32512 0.175006)
			(stroke
				(width 0.1)
				(type default)
			)
			(layer "B.Fab")
		)
		(fp_line
			(start -0.32512 -0.175006)
			(end -0.32512 0.175006)
			(stroke
				(width 0.1)
				(type default)
			)
			(layer "B.Fab")
		)
		(pad "1" smd rect
			(at 0.2667 0)
			(size 0.3048 0.381)
			(layers "B.Cu" "B.Mask" "B.Paste")
			(net "P1V8_CPU0_RT_1D")
		)
		(pad "2" smd rect
			(at -0.2667 0 180)
			(size 0.3048 0.381)
			(layers "B.Cu" "B.Mask" "B.Paste")
			(net "SMB_RT_CPU0_P2_ROM_MUX_2D_R_SCL")
		)
	)
)
